(kicad_pcb
	(version 20260206)
	(generator "pcbnew")
	(generator_version "10.0")
	(general
		(thickness 1.6)
		(legacy_teardrops no)
	)
	(paper "A4")
	(title_block
		(title "panther-plus-userver — 13130-1b_20150205.brd")
		(comment 1 "Honey Badger (Wiwynn) / footprint 1214 of 1509 (DIMM3), pads 121-127 of 210")
	)
	(layers
		(0 "F.Cu" signal "TOP")
		(4 "In1.Cu" signal "L2")
		(6 "In2.Cu" signal "L3")
		(8 "In3.Cu" signal "L4")
		(10 "In4.Cu" signal "L5")
		(12 "In5.Cu" signal "L6")
		(14 "In6.Cu" signal "L7")
		(16 "In7.Cu" signal "L8")
		(18 "In8.Cu" signal "L9")
		(20 "In9.Cu" signal "L10")
		(22 "In10.Cu" signal "L11")
		(2 "B.Cu" signal "BOTTOM")
		(9 "F.Adhes" user "F.Adhesive")
		(11 "B.Adhes" user "B.Adhesive")
		(13 "F.Paste" user "Package Geometry/Pastemask Top")
		(15 "B.Paste" user "Package Geometry/Pastemask Bottom")
		(5 "F.SilkS" user "Ref Des/Silkscreen Top")
		(7 "B.SilkS" user "Ref Des/Silkscreen Bottom")
		(1 "F.Mask" user "Board Geometry/Soldermask Top")
		(3 "B.Mask" user "Board Geometry/Soldermask Bottom")
		(17 "Dwgs.User" user "User.Drawings")
		(19 "Cmts.User" user "User.Comments")
		(21 "Eco1.User" user "User.Eco1")
		(23 "Eco2.User" user "User.Eco2")
		(25 "Edge.Cuts" user "Board Geometry/Outline")
		(27 "Margin" user)
		(31 "F.CrtYd" user "Package Geometry/Place Bound Top")
		(29 "B.CrtYd" user "Package Geometry/Place Bound Bottom")
		(35 "F.Fab" user "Ref Des/Assembly Top")
		(33 "B.Fab" user "Ref Des/Assembly Bottom")
	)
	(footprint ""
		(layer "B.Cu")
		(at 159.999934 -5.790692)
		(property "Reference" "DIMM3"
			(at 0 0 0)
			(layer "B.SilkS")
			(hide yes)
			(effects
				(font
					(size 1.27 1.27)
				)
				(justify mirror)
			)
		)
		(property "Value" "DDR3-204P-142-COLAY-1-GP-U"
			(at 41.312338 -16.676878 0)
			(unlocked yes)
			(layer "B.Fab")
			(hide yes)
			(effects
				(font
					(size 1.016 1.016)
					(thickness 0.1524)
				)
				(justify mirror)
			)
		)
		(property "Device Type" "AS0A626-J8R6-7H-COLAY-1"
			(at 41.312338 -18.200878 0)
			(unlocked yes)
			(layer "B.Fab")
			(hide yes)
			(effects
				(font
					(size 1.016 1.016)
					(thickness 0.1524)
				)
				(justify mirror)
			)
		)
		(duplicate_pad_numbers_are_jumpers no)
		(pad "119" smd custom
			(at 6.150102 -4.100068 180)
			(size 0.1143 0.1143)
			(layers "B.Cu" "B.Mask" "B.Paste")
			(net "M_B_BS0")
			(options
				(clearance outline)
				(anchor circle)
			)
			(primitives
				(gr_poly
					(pts
						(xy 0 -0.9017) (xy -0.03175 -0.89916) (xy -0.0635 -0.889) (xy -0.09144 -0.87376) (xy -0.11684 -0.85344)
						(xy -0.13716 -0.82804) (xy -0.1524 -0.8001) (xy -0.16256 -0.76835) (xy -0.1651 -0.7366) (xy -0.1651 -0.19685)
						(xy -0.17272 -0.18923) (xy -0.17907 -0.18034) (xy -0.18669 -0.17145) (xy -0.19177 -0.16256) (xy -0.19812 -0.15367)
						(xy -0.20828 -0.13335) (xy -0.21971 -0.10287) (xy -0.22225 -0.09271) (xy -0.22479 -0.08128) (xy -0.22606 -0.07112)
						(xy -0.2286 -0.05969) (xy -0.2286 -0.01651) (xy -0.22606 -0.00508) (xy -0.22479 0.00508) (xy -0.22225 0.01651)
						(xy -0.21971 0.02667) (xy -0.20828 0.05715) (xy -0.19812 0.07747) (xy -0.19177 0.08636) (xy -0.18669 0.09525)
						(xy -0.17907 0.10414) (xy -0.17272 0.11303) (xy -0.1651 0.12065) (xy -0.1651 0.7366) (xy -0.16256 0.76835)
						(xy -0.1524 0.8001) (xy -0.13716 0.82804) (xy -0.11684 0.85344) (xy -0.09144 0.87376) (xy -0.0635 0.889)
						(xy -0.03175 0.89916) (xy 0 0.9017) (xy 0.03175 0.89916) (xy 0.0635 0.889) (xy 0.09144 0.87376)
						(xy 0.11684 0.85344) (xy 0.13716 0.82804) (xy 0.1524 0.8001) (xy 0.16256 0.76835) (xy 0.1651 0.7366)
						(xy 0.1651 0.11938) (xy 0.17272 0.11176) (xy 0.19812 0.0762) (xy 0.2032 0.06604) (xy 0.20701 0.05715)
						(xy 0.21209 0.04699) (xy 0.2159 0.03683) (xy 0.21844 0.02667) (xy 0.22225 0.01524) (xy 0.22352 0.00508)
						(xy 0.22606 -0.00508) (xy 0.22733 -0.01651) (xy 0.22733 -0.02667) (xy 0.2286 -0.0381) (xy 0.22733 -0.04953)
						(xy 0.22733 -0.05969) (xy 0.22606 -0.07112) (xy 0.22352 -0.08128) (xy 0.22225 -0.09144) (xy 0.21844 -0.10287)
						(xy 0.2159 -0.11303) (xy 0.21209 -0.12319) (xy 0.20701 -0.13335) (xy 0.2032 -0.14224) (xy 0.19812 -0.1524)
						(xy 0.17272 -0.18796) (xy 0.1651 -0.19558) (xy 0.1651 -0.7366) (xy 0.16256 -0.76835) (xy 0.1524 -0.8001)
						(xy 0.13716 -0.82804) (xy 0.11684 -0.85344) (xy 0.09144 -0.87376) (xy 0.0635 -0.889) (xy 0.03175 -0.89916)
					)
					(width 0)
					(fill yes)
				)
			)
		)
		(pad "120" smd custom
			(at 6.450076 4.100068 180)
			(size 0.1143 0.1143)
			(layers "B.Cu" "B.Mask" "B.Paste")
			(net "Net_7")
			(options
				(clearance outline)
				(anchor circle)
			)
			(primitives
				(gr_poly
					(pts
						(xy 0 -0.9017) (xy -0.03175 -0.89916) (xy -0.0635 -0.889) (xy -0.09144 -0.87376) (xy -0.11684 -0.85344)
						(xy -0.13716 -0.82804) (xy -0.1524 -0.8001) (xy -0.16256 -0.76835) (xy -0.1651 -0.7366) (xy -0.1651 -0.11938)
						(xy -0.17272 -0.11176) (xy -0.19812 -0.0762) (xy -0.2032 -0.06604) (xy -0.20701 -0.05715) (xy -0.21209 -0.04699)
						(xy -0.2159 -0.03683) (xy -0.21844 -0.02667) (xy -0.22225 -0.01524) (xy -0.22352 -0.00508) (xy -0.22606 0.00508)
						(xy -0.22733 0.01651) (xy -0.22733 0.02667) (xy -0.2286 0.0381) (xy -0.22733 0.04953) (xy -0.22733 0.05969)
						(xy -0.22606 0.07112) (xy -0.22352 0.08128) (xy -0.22225 0.09144) (xy -0.21844 0.10287) (xy -0.2159 0.11303)
						(xy -0.21209 0.12319) (xy -0.20701 0.13335) (xy -0.2032 0.14224) (xy -0.19812 0.1524) (xy -0.17272 0.18796)
						(xy -0.1651 0.19558) (xy -0.1651 0.7366) (xy -0.16256 0.76835) (xy -0.1524 0.8001) (xy -0.13716 0.82804)
						(xy -0.11684 0.85344) (xy -0.09144 0.87376) (xy -0.0635 0.889) (xy -0.03175 0.89916) (xy 0 0.9017)
						(xy 0.03175 0.89916) (xy 0.0635 0.889) (xy 0.09144 0.87376) (xy 0.11684 0.85344) (xy 0.13716 0.82804)
						(xy 0.1524 0.8001) (xy 0.16256 0.76835) (xy 0.1651 0.7366) (xy 0.1651 0.19685) (xy 0.17272 0.18923)
						(xy 0.17907 0.18034) (xy 0.18669 0.17145) (xy 0.19177 0.16256) (xy 0.19812 0.15367) (xy 0.20828 0.13335)
						(xy 0.21971 0.10287) (xy 0.22225 0.09271) (xy 0.22479 0.08128) (xy 0.22606 0.07112) (xy 0.2286 0.05969)
						(xy 0.2286 0.01651) (xy 0.22606 0.00508) (xy 0.22479 -0.00508) (xy 0.22225 -0.01651) (xy 0.21971 -0.02667)
						(xy 0.20828 -0.05715) (xy 0.19812 -0.07747) (xy 0.19177 -0.08636) (xy 0.18669 -0.09525) (xy 0.17907 -0.10414)
						(xy 0.17272 -0.11303) (xy 0.1651 -0.12065) (xy 0.1651 -0.7366) (xy 0.16256 -0.76835) (xy 0.1524 -0.8001)
						(xy 0.13716 -0.82804) (xy 0.11684 -0.85344) (xy 0.09144 -0.87376) (xy 0.0635 -0.889) (xy 0.03175 -0.89916)
					)
					(width 0)
					(fill yes)
				)
			)
		)
		(pad "121" smd custom
			(at 6.75005 -4.100068 180)
			(size 0.1143 0.1143)
			(layers "B.Cu" "B.Mask" "B.Paste")
			(net "M_B_WE#")
			(options
				(clearance outline)
				(anchor circle)
			)
			(primitives
				(gr_poly
					(pts
						(xy 0 -0.9017) (xy -0.03175 -0.89916) (xy -0.0635 -0.889) (xy -0.09144 -0.87376) (xy -0.11684 -0.85344)
						(xy -0.13716 -0.82804) (xy -0.1524 -0.8001) (xy -0.16256 -0.76835) (xy -0.1651 -0.7366) (xy -0.1651 -0.44958)
						(xy -0.17272 -0.44196) (xy -0.19812 -0.4064) (xy -0.2032 -0.39624) (xy -0.20701 -0.38735) (xy -0.21209 -0.37719)
						(xy -0.2159 -0.36703) (xy -0.21844 -0.35687) (xy -0.22225 -0.34544) (xy -0.22352 -0.33528) (xy -0.22606 -0.32512)
						(xy -0.22733 -0.31369) (xy -0.22733 -0.30353) (xy -0.2286 -0.2921) (xy -0.22733 -0.28067) (xy -0.22733 -0.27051)
						(xy -0.22606 -0.25908) (xy -0.22352 -0.24892) (xy -0.22225 -0.23876) (xy -0.21844 -0.22733) (xy -0.2159 -0.21717)
						(xy -0.21209 -0.20701) (xy -0.20701 -0.19685) (xy -0.2032 -0.18796) (xy -0.19812 -0.1778) (xy -0.17272 -0.14224)
						(xy -0.1651 -0.13462) (xy -0.1651 0.7366) (xy -0.16256 0.76835) (xy -0.1524 0.8001) (xy -0.13716 0.82804)
						(xy -0.11684 0.85344) (xy -0.09144 0.87376) (xy -0.0635 0.889) (xy -0.03175 0.89916) (xy 0 0.9017)
						(xy 0.03175 0.89916) (xy 0.0635 0.889) (xy 0.09144 0.87376) (xy 0.11684 0.85344) (xy 0.13716 0.82804)
						(xy 0.1524 0.8001) (xy 0.16256 0.76835) (xy 0.1651 0.7366) (xy 0.1651 -0.13462) (xy 0.17272 -0.14224)
						(xy 0.19812 -0.1778) (xy 0.2032 -0.18796) (xy 0.20701 -0.19685) (xy 0.21209 -0.20701) (xy 0.2159 -0.21717)
						(xy 0.21844 -0.22733) (xy 0.22225 -0.23876) (xy 0.22352 -0.24892) (xy 0.22606 -0.25908) (xy 0.22733 -0.27051)
						(xy 0.22733 -0.28067) (xy 0.2286 -0.2921) (xy 0.22733 -0.30353) (xy 0.22733 -0.31369) (xy 0.22606 -0.32512)
						(xy 0.22352 -0.33528) (xy 0.22225 -0.34544) (xy 0.21844 -0.35687) (xy 0.2159 -0.36703) (xy 0.21209 -0.37719)
						(xy 0.20701 -0.38735) (xy 0.2032 -0.39624) (xy 0.19812 -0.4064) (xy 0.17272 -0.44196) (xy 0.1651 -0.44958)
						(xy 0.1651 -0.7366) (xy 0.16256 -0.76835) (xy 0.1524 -0.8001) (xy 0.13716 -0.82804) (xy 0.11684 -0.85344)
						(xy 0.09144 -0.87376) (xy 0.0635 -0.889) (xy 0.03175 -0.89916)
					)
					(width 0)
					(fill yes)
				)
			)
		)
		(pad "122" smd custom
			(at 7.050024 4.100068 180)
			(size 0.1143 0.1143)
			(layers "B.Cu" "B.Mask" "B.Paste")
			(net "M_B_RAS#")
			(options
				(clearance outline)
				(anchor circle)
			)
			(primitives
				(gr_poly
					(pts
						(xy 0 -0.9017) (xy -0.03175 -0.89916) (xy -0.0635 -0.889) (xy -0.09144 -0.87376) (xy -0.11684 -0.85344)
						(xy -0.13716 -0.82804) (xy -0.1524 -0.8001) (xy -0.16256 -0.76835) (xy -0.1651 -0.7366) (xy -0.1651 0.13462)
						(xy -0.17272 0.14224) (xy -0.19812 0.1778) (xy -0.2032 0.18796) (xy -0.20701 0.19685) (xy -0.21209 0.20701)
						(xy -0.2159 0.21717) (xy -0.21844 0.22733) (xy -0.22225 0.23876) (xy -0.22352 0.24892) (xy -0.22606 0.25908)
						(xy -0.22733 0.27051) (xy -0.22733 0.28067) (xy -0.2286 0.2921) (xy -0.22733 0.30353) (xy -0.22733 0.31369)
						(xy -0.22606 0.32512) (xy -0.22352 0.33528) (xy -0.22225 0.34544) (xy -0.21844 0.35687) (xy -0.2159 0.36703)
						(xy -0.21209 0.37719) (xy -0.20701 0.38735) (xy -0.2032 0.39624) (xy -0.19812 0.4064) (xy -0.17272 0.44196)
						(xy -0.1651 0.44958) (xy -0.1651 0.7366) (xy -0.16256 0.76835) (xy -0.1524 0.8001) (xy -0.13716 0.82804)
						(xy -0.11684 0.85344) (xy -0.09144 0.87376) (xy -0.0635 0.889) (xy -0.03175 0.89916) (xy 0 0.9017)
						(xy 0.03175 0.89916) (xy 0.0635 0.889) (xy 0.09144 0.87376) (xy 0.11684 0.85344) (xy 0.13716 0.82804)
						(xy 0.1524 0.8001) (xy 0.16256 0.76835) (xy 0.1651 0.7366) (xy 0.1651 0.44958) (xy 0.17272 0.44196)
						(xy 0.19812 0.4064) (xy 0.2032 0.39624) (xy 0.20701 0.38735) (xy 0.21209 0.37719) (xy 0.2159 0.36703)
						(xy 0.21844 0.35687) (xy 0.22225 0.34544) (xy 0.22352 0.33528) (xy 0.22606 0.32512) (xy 0.22733 0.31369)
						(xy 0.22733 0.30353) (xy 0.2286 0.2921) (xy 0.22733 0.28067) (xy 0.22733 0.27051) (xy 0.22606 0.25908)
						(xy 0.22352 0.24892) (xy 0.22225 0.23876) (xy 0.21844 0.22733) (xy 0.2159 0.21717) (xy 0.21209 0.20701)
						(xy 0.20701 0.19685) (xy 0.2032 0.18796) (xy 0.19812 0.1778) (xy 0.17272 0.14224) (xy 0.1651 0.13462)
						(xy 0.1651 -0.7366) (xy 0.16256 -0.76835) (xy 0.1524 -0.8001) (xy 0.13716 -0.82804) (xy 0.11684 -0.85344)
						(xy 0.09144 -0.87376) (xy 0.0635 -0.889) (xy 0.03175 -0.89916)
					)
					(width 0)
					(fill yes)
				)
			)
		)
		(pad "123" smd custom
			(at 7.349998 -4.100068 180)
			(size 0.1143 0.1143)
			(layers "B.Cu" "B.Mask" "B.Paste")
			(net "PV_VDDR")
			(options
				(clearance outline)
				(anchor circle)
			)
			(primitives
				(gr_poly
					(pts
						(xy 0 -0.9017) (xy -0.03175 -0.89916) (xy -0.0635 -0.889) (xy -0.09144 -0.87376) (xy -0.11684 -0.85344)
						(xy -0.13716 -0.82804) (xy -0.1524 -0.8001) (xy -0.16256 -0.76835) (xy -0.1651 -0.7366) (xy -0.1651 -0.19685)
						(xy -0.17272 -0.18923) (xy -0.17907 -0.18034) (xy -0.18669 -0.17145) (xy -0.19177 -0.16256) (xy -0.19812 -0.15367)
						(xy -0.20828 -0.13335) (xy -0.21971 -0.10287) (xy -0.22225 -0.09271) (xy -0.22479 -0.08128) (xy -0.22606 -0.07112)
						(xy -0.2286 -0.05969) (xy -0.2286 -0.01651) (xy -0.22606 -0.00508) (xy -0.22479 0.00508) (xy -0.22225 0.01651)
						(xy -0.21971 0.02667) (xy -0.20828 0.05715) (xy -0.19812 0.07747) (xy -0.19177 0.08636) (xy -0.18669 0.09525)
						(xy -0.17907 0.10414) (xy -0.17272 0.11303) (xy -0.1651 0.12065) (xy -0.1651 0.7366) (xy -0.16256 0.76835)
						(xy -0.1524 0.8001) (xy -0.13716 0.82804) (xy -0.11684 0.85344) (xy -0.09144 0.87376) (xy -0.0635 0.889)
						(xy -0.03175 0.89916) (xy 0 0.9017) (xy 0.03175 0.89916) (xy 0.0635 0.889) (xy 0.09144 0.87376)
						(xy 0.11684 0.85344) (xy 0.13716 0.82804) (xy 0.1524 0.8001) (xy 0.16256 0.76835) (xy 0.1651 0.7366)
						(xy 0.1651 0.11938) (xy 0.17272 0.11176) (xy 0.19812 0.0762) (xy 0.2032 0.06604) (xy 0.20701 0.05715)
						(xy 0.21209 0.04699) (xy 0.2159 0.03683) (xy 0.21844 0.02667) (xy 0.22225 0.01524) (xy 0.22352 0.00508)
						(xy 0.22606 -0.00508) (xy 0.22733 -0.01651) (xy 0.22733 -0.02667) (xy 0.2286 -0.0381) (xy 0.22733 -0.04953)
						(xy 0.22733 -0.05969) (xy 0.22606 -0.07112) (xy 0.22352 -0.08128) (xy 0.22225 -0.09144) (xy 0.21844 -0.10287)
						(xy 0.2159 -0.11303) (xy 0.21209 -0.12319) (xy 0.20701 -0.13335) (xy 0.2032 -0.14224) (xy 0.19812 -0.1524)
						(xy 0.17272 -0.18796) (xy 0.1651 -0.19558) (xy 0.1651 -0.7366) (xy 0.16256 -0.76835) (xy 0.1524 -0.8001)
						(xy 0.13716 -0.82804) (xy 0.11684 -0.85344) (xy 0.09144 -0.87376) (xy 0.0635 -0.889) (xy 0.03175 -0.89916)
					)
					(width 0)
					(fill yes)
				)
			)
		)
		(pad "124" smd custom
			(at 7.649972 4.100068 180)
			(size 0.1143 0.1143)
			(layers "B.Cu" "B.Mask" "B.Paste")
			(net "PV_VDDR")
			(options
				(clearance outline)
				(anchor circle)
			)
			(primitives
				(gr_poly
					(pts
						(xy 0 -0.9017) (xy -0.03175 -0.89916) (xy -0.0635 -0.889) (xy -0.09144 -0.87376) (xy -0.11684 -0.85344)
						(xy -0.13716 -0.82804) (xy -0.1524 -0.8001) (xy -0.16256 -0.76835) (xy -0.1651 -0.7366) (xy -0.1651 -0.11938)
						(xy -0.17272 -0.11176) (xy -0.19812 -0.0762) (xy -0.2032 -0.06604) (xy -0.20701 -0.05715) (xy -0.21209 -0.04699)
						(xy -0.2159 -0.03683) (xy -0.21844 -0.02667) (xy -0.22225 -0.01524) (xy -0.22352 -0.00508) (xy -0.22606 0.00508)
						(xy -0.22733 0.01651) (xy -0.22733 0.02667) (xy -0.2286 0.0381) (xy -0.22733 0.04953) (xy -0.22733 0.05969)
						(xy -0.22606 0.07112) (xy -0.22352 0.08128) (xy -0.22225 0.09144) (xy -0.21844 0.10287) (xy -0.2159 0.11303)
						(xy -0.21209 0.12319) (xy -0.20701 0.13335) (xy -0.2032 0.14224) (xy -0.19812 0.1524) (xy -0.17272 0.18796)
						(xy -0.1651 0.19558) (xy -0.1651 0.7366) (xy -0.16256 0.76835) (xy -0.1524 0.8001) (xy -0.13716 0.82804)
						(xy -0.11684 0.85344) (xy -0.09144 0.87376) (xy -0.0635 0.889) (xy -0.03175 0.89916) (xy 0 0.9017)
						(xy 0.03175 0.89916) (xy 0.0635 0.889) (xy 0.09144 0.87376) (xy 0.11684 0.85344) (xy 0.13716 0.82804)
						(xy 0.1524 0.8001) (xy 0.16256 0.76835) (xy 0.1651 0.7366) (xy 0.1651 0.19685) (xy 0.17272 0.18923)
						(xy 0.17907 0.18034) (xy 0.18669 0.17145) (xy 0.19177 0.16256) (xy 0.19812 0.15367) (xy 0.20828 0.13335)
						(xy 0.21971 0.10287) (xy 0.22225 0.09271) (xy 0.22479 0.08128) (xy 0.22606 0.07112) (xy 0.2286 0.05969)
						(xy 0.2286 0.01651) (xy 0.22606 0.00508) (xy 0.22479 -0.00508) (xy 0.22225 -0.01651) (xy 0.21971 -0.02667)
						(xy 0.20828 -0.05715) (xy 0.19812 -0.07747) (xy 0.19177 -0.08636) (xy 0.18669 -0.09525) (xy 0.17907 -0.10414)
						(xy 0.17272 -0.11303) (xy 0.1651 -0.12065) (xy 0.1651 -0.7366) (xy 0.16256 -0.76835) (xy 0.1524 -0.8001)
						(xy 0.13716 -0.82804) (xy 0.11684 -0.85344) (xy 0.09144 -0.87376) (xy 0.0635 -0.889) (xy 0.03175 -0.89916)
					)
					(width 0)
					(fill yes)
				)
			)
		)
		(pad "125" smd custom
			(at 7.949946 -4.100068 180)
			(size 0.1143 0.1143)
			(layers "B.Cu" "B.Mask" "B.Paste")
			(net "M_B_CAS#")
			(options
				(clearance outline)
				(anchor circle)
			)
			(primitives
				(gr_poly
					(pts
						(xy 0 -0.9017) (xy -0.03175 -0.89916) (xy -0.0635 -0.889) (xy -0.09144 -0.87376) (xy -0.11684 -0.85344)
						(xy -0.13716 -0.82804) (xy -0.1524 -0.8001) (xy -0.16256 -0.76835) (xy -0.1651 -0.7366) (xy -0.1651 -0.44958)
						(xy -0.17272 -0.44196) (xy -0.19812 -0.4064) (xy -0.2032 -0.39624) (xy -0.20701 -0.38735) (xy -0.21209 -0.37719)
						(xy -0.2159 -0.36703) (xy -0.21844 -0.35687) (xy -0.22225 -0.34544) (xy -0.22352 -0.33528) (xy -0.22606 -0.32512)
						(xy -0.22733 -0.31369) (xy -0.22733 -0.30353) (xy -0.2286 -0.2921) (xy -0.22733 -0.28067) (xy -0.22733 -0.27051)
						(xy -0.22606 -0.25908) (xy -0.22352 -0.24892) (xy -0.22225 -0.23876) (xy -0.21844 -0.22733) (xy -0.2159 -0.21717)
						(xy -0.21209 -0.20701) (xy -0.20701 -0.19685) (xy -0.2032 -0.18796) (xy -0.19812 -0.1778) (xy -0.17272 -0.14224)
						(xy -0.1651 -0.13462) (xy -0.1651 0.7366) (xy -0.16256 0.76835) (xy -0.1524 0.8001) (xy -0.13716 0.82804)
						(xy -0.11684 0.85344) (xy -0.09144 0.87376) (xy -0.0635 0.889) (xy -0.03175 0.89916) (xy 0 0.9017)
						(xy 0.03175 0.89916) (xy 0.0635 0.889) (xy 0.09144 0.87376) (xy 0.11684 0.85344) (xy 0.13716 0.82804)
						(xy 0.1524 0.8001) (xy 0.16256 0.76835) (xy 0.1651 0.7366) (xy 0.1651 -0.13462) (xy 0.17272 -0.14224)
						(xy 0.19812 -0.1778) (xy 0.2032 -0.18796) (xy 0.20701 -0.19685) (xy 0.21209 -0.20701) (xy 0.2159 -0.21717)
						(xy 0.21844 -0.22733) (xy 0.22225 -0.23876) (xy 0.22352 -0.24892) (xy 0.22606 -0.25908) (xy 0.22733 -0.27051)
						(xy 0.22733 -0.28067) (xy 0.2286 -0.2921) (xy 0.22733 -0.30353) (xy 0.22733 -0.31369) (xy 0.22606 -0.32512)
						(xy 0.22352 -0.33528) (xy 0.22225 -0.34544) (xy 0.21844 -0.35687) (xy 0.2159 -0.36703) (xy 0.21209 -0.37719)
						(xy 0.20701 -0.38735) (xy 0.2032 -0.39624) (xy 0.19812 -0.4064) (xy 0.17272 -0.44196) (xy 0.1651 -0.44958)
						(xy 0.1651 -0.7366) (xy 0.16256 -0.76835) (xy 0.1524 -0.8001) (xy 0.13716 -0.82804) (xy 0.11684 -0.85344)
						(xy 0.09144 -0.87376) (xy 0.0635 -0.889) (xy 0.03175 -0.89916)
					)
					(width 0)
					(fill yes)
				)
			)
		)
	)
)
